# S9S_MB_2U (Grand Teton) — schematic netlist excerpt (pin names and nets, part order shuffled) for the footprints in the layout excerpt that follows; sources: Cadence DE-HDL packaged netlist, KiCad conversion of 03242023_DA0F0TMBIJ0_F0T_Motherboard_J_brd_V01_OCP.brd

PC603_P0_2  Q_CAP  3300PF 50V 10% X7R  pkg 0402  page 271 : A = SW_P12V_PVCCFA_EHV_FIVRA_CPU0_L ; B = GND
R4653  Q_RES  1K 1% CHIP  pkg 0402LF  page 167 : A = FM_P2E_BUF2_VODB_DB ; B = GND

(kicad_pcb
	(version 20260206)
	(generator "pcbnew")
	(generator_version "10.0")
	(general
		(thickness 1.6)
		(legacy_teardrops no)
	)
	(paper "A4")
	(title_block
		(title "03242023_DA0F0TMBIJ0_F0T_Motherboard_J_brd_V01_OCP.brd")
		(comment 1 "Grand Teton / footprints 736-737 of 6105")
	)
	(layers
		(0 "F.Cu" signal "TOP")
		(4 "In1.Cu" signal "GND")
		(6 "In2.Cu" signal "IN1")
		(8 "In3.Cu" signal "GND1")
		(10 "In4.Cu" signal "IN2")
		(12 "In5.Cu" signal "GND2")
		(14 "In6.Cu" signal "IN3")
		(16 "In7.Cu" signal "GND3")
		(18 "In8.Cu" signal "VCC")
		(20 "In9.Cu" signal "VCC1")
		(22 "In10.Cu" signal "GND4")
		(24 "In11.Cu" signal "IN4")
		(26 "In12.Cu" signal "GND5")
		(28 "In13.Cu" signal "IN5")
		(30 "In14.Cu" signal "GND6")
		(32 "In15.Cu" signal "IN6")
		(34 "In16.Cu" signal "GND7")
		(2 "B.Cu" signal "BOTTOM")
		(9 "F.Adhes" user "F.Adhesive")
		(11 "B.Adhes" user "B.Adhesive")
		(13 "F.Paste" user "Package Geometry/Pastemask Top")
		(15 "B.Paste" user "Package Geometry/Pastemask Bottom")
		(5 "F.SilkS" user "Ref Des/Silkscreen Top")
		(7 "B.SilkS" user "Ref Des/Silkscreen Bottom")
		(1 "F.Mask" user "Board Geometry/Soldermask Top")
		(3 "B.Mask" user "Board Geometry/Soldermask Bottom")
		(17 "Dwgs.User" user "User.Drawings")
		(19 "Cmts.User" user "User.Comments")
		(21 "Eco1.User" user "User.Eco1")
		(23 "Eco2.User" user "User.Eco2")
		(25 "Edge.Cuts" user "Board Geometry/Outline")
		(27 "Margin" user)
		(31 "F.CrtYd" user "Package Geometry/Place Bound Top")
		(29 "B.CrtYd" user "Package Geometry/Place Bound Bottom")
		(35 "F.Fab" user "Ref Des/Assembly Top")
		(33 "B.Fab" user "Ref Des/Assembly Bottom")
	)
	(footprint ""
		(layer "F.Cu")
		(at 302.045624 -362.843826 -90)
		(property "Reference" "PC603_P0_2"
			(at 0 0 270)
			(layer "F.SilkS")
			(hide yes)
			(effects
				(font
					(size 1.27 1.27)
				)
			)
		)
		(property "Value" ""
			(at 0 0 270)
			(layer "F.Fab")
			(effects
				(font
					(size 1.27 1.27)
				)
			)
		)
		(duplicate_pad_numbers_are_jumpers no)
		(fp_line
			(start -0.7874 0.4064)
			(end -0.7874 -0.4064)
			(stroke
				(width 0.1524)
				(type default)
			)
			(layer "F.SilkS")
		)
		(fp_line
			(start 0.7874 0.4064)
			(end -0.7874 0.4064)
			(stroke
				(width 0.1524)
				(type default)
			)
			(layer "F.SilkS")
		)
		(fp_line
			(start -0.7874 -0.4064)
			(end 0.7874 -0.4064)
			(stroke
				(width 0.1524)
				(type default)
			)
			(layer "F.SilkS")
		)
		(fp_line
			(start 0.7874 -0.4064)
			(end 0.7874 0.4064)
			(stroke
				(width 0.1524)
				(type default)
			)
			(layer "F.SilkS")
		)
		(fp_line
			(start -0.67945 0.3048)
			(end -0.67945 -0.305054)
			(stroke
				(width 0.1)
				(type default)
			)
			(layer "F.Fab")
		)
		(fp_line
			(start -0.12065 0.3048)
			(end -0.67945 0.3048)
			(stroke
				(width 0.1)
				(type default)
			)
			(layer "F.Fab")
		)
		(fp_line
			(start 0.120396 0.3048)
			(end 0.120396 0.2794)
			(stroke
				(width 0.1)
				(type default)
			)
			(layer "F.Fab")
		)
		(fp_line
			(start 0.67945 0.3048)
			(end 0.120396 0.3048)
			(stroke
				(width 0.1)
				(type default)
			)
			(layer "F.Fab")
		)
		(fp_line
			(start -0.12065 0.2794)
			(end -0.12065 0.3048)
			(stroke
				(width 0.1)
				(type default)
			)
			(layer "F.Fab")
		)
		(fp_line
			(start 0.120396 0.2794)
			(end -0.12065 0.2794)
			(stroke
				(width 0.1)
				(type default)
			)
			(layer "F.Fab")
		)
		(fp_line
			(start -0.12065 -0.2794)
			(end 0.12065 -0.2794)
			(stroke
				(width 0.1)
				(type default)
			)
			(layer "F.Fab")
		)
		(fp_line
			(start 0.12065 -0.2794)
			(end 0.12065 -0.3048)
			(stroke
				(width 0.1)
				(type default)
			)
			(layer "F.Fab")
		)
		(fp_line
			(start 0.12065 -0.3048)
			(end 0.67945 -0.3048)
			(stroke
				(width 0.1)
				(type default)
			)
			(layer "F.Fab")
		)
		(fp_line
			(start 0.67945 -0.3048)
			(end 0.67945 0.3048)
			(stroke
				(width 0.1)
				(type default)
			)
			(layer "F.Fab")
		)
		(fp_line
			(start -0.67945 -0.305054)
			(end -0.12065 -0.305054)
			(stroke
				(width 0.1)
				(type default)
			)
			(layer "F.Fab")
		)
		(fp_line
			(start -0.12065 -0.305054)
			(end -0.12065 -0.2794)
			(stroke
				(width 0.1)
				(type default)
			)
			(layer "F.Fab")
		)
		(pad "1" smd circle
			(at -0.40005 0 270)
			(size 0 0)
			(layers "F.Cu" "F.Mask" "F.Paste")
			(net "SW_P12V_PVCCFA_EHV_FIVRA_CPU0_L")
		)
		(pad "2" smd circle
			(at 0.40005 0 270)
			(size 0 0)
			(layers "F.Cu" "F.Mask" "F.Paste")
			(net "GND")
		)
	)
	(footprint ""
		(layer "F.Cu")
		(at 46.085506 -394.429996)
		(property "Reference" "R4653"
			(at 0 0 0)
			(layer "F.SilkS")
			(hide yes)
			(effects
				(font
					(size 1.27 1.27)
				)
			)
		)
		(property "Value" ""
			(at 0 0 0)
			(layer "F.Fab")
			(effects
				(font
					(size 1.27 1.27)
				)
			)
		)
		(duplicate_pad_numbers_are_jumpers no)
		(fp_line
			(start -0.7874 -0.4064)
			(end 0.7874 -0.4064)
			(stroke
				(width 0.1524)
				(type default)
			)
			(layer "F.SilkS")
		)
		(fp_line
			(start -0.7874 0.4064)
			(end -0.7874 -0.4064)
			(stroke
				(width 0.1524)
				(type default)
			)
			(layer "F.SilkS")
		)
		(fp_line
			(start 0.7874 -0.4064)
			(end 0.7874 0.4064)
			(stroke
				(width 0.1524)
				(type default)
			)
			(layer "F.SilkS")
		)
		(fp_line
			(start 0.7874 0.4064)
			(end -0.7874 0.4064)
			(stroke
				(width 0.1524)
				(type default)
			)
			(layer "F.SilkS")
		)
		(fp_line
			(start -0.67945 -0.305054)
			(end -0.12065 -0.305054)
			(stroke
				(width 0.1)
				(type default)
			)
			(layer "F.Fab")
		)
		(fp_line
			(start -0.67945 0.3048)
			(end -0.67945 -0.305054)
			(stroke
				(width 0.1)
				(type default)
			)
			(layer "F.Fab")
		)
		(fp_line
			(start -0.12065 -0.305054)
			(end -0.12065 -0.2794)
			(stroke
				(width 0.1)
				(type default)
			)
			(layer "F.Fab")
		)
		(fp_line
			(start -0.12065 -0.2794)
			(end 0.12065 -0.2794)
			(stroke
				(width 0.1)
				(type default)
			)
			(layer "F.Fab")
		)
		(fp_line
			(start -0.12065 0.2794)
			(end -0.12065 0.3048)
			(stroke
				(width 0.1)
				(type default)
			)
			(layer "F.Fab")
		)
		(fp_line
			(start -0.12065 0.3048)
			(end -0.67945 0.3048)
			(stroke
				(width 0.1)
				(type default)
			)
			(layer "F.Fab")
		)
		(fp_line
			(start 0.120396 0.2794)
			(end -0.12065 0.2794)
			(stroke
				(width 0.1)
				(type default)
			)
			(layer "F.Fab")
		)
		(fp_line
			(start 0.120396 0.3048)
			(end 0.120396 0.2794)
			(stroke
				(width 0.1)
				(type default)
			)
			(layer "F.Fab")
		)
		(fp_line
			(start 0.12065 -0.3048)
			(end 0.67945 -0.3048)
			(stroke
				(width 0.1)
				(type default)
			)
			(layer "F.Fab")
		)
		(fp_line
			(start 0.12065 -0.2794)
			(end 0.12065 -0.3048)
			(stroke
				(width 0.1)
				(type default)
			)
			(layer "F.Fab")
		)
		(fp_line
			(start 0.67945 -0.3048)
			(end 0.67945 0.3048)
			(stroke
				(width 0.1)
				(type default)
			)
			(layer "F.Fab")
		)
		(fp_line
			(start 0.67945 0.3048)
			(end 0.120396 0.3048)
			(stroke
				(width 0.1)
				(type default)
			)
			(layer "F.Fab")
		)
		(pad "1" smd circle
			(at -0.40005 0)
			(size 0 0)
			(layers "F.Cu" "F.Mask" "F.Paste")
			(net "FM_P2E_BUF2_VODB_DB")
		)
		(pad "2" smd circle
			(at 0.40005 0)
			(size 0 0)
			(layers "F.Cu" "F.Mask" "F.Paste")
			(net "GND")
		)
	)
)
